FILE_TYPE = MULTI_PHYS_TABLE;
PART 'RES_PWR'
{==============================================================================================================================================================================================================================================================}
:VALUE     | TOLERANCE | WATTAGE | PACK_TYPE | MATERIAL | PART_NUMBER     = EnvComp                  |  PART_NUMBER | JEDEC_TYPE | ALT_SYMBOLS   | VALUE    | TOL    | WATTAGE | CLASS      | DESCRIPTION                                  | HEIGHT     | COMPONENT_TYPE | LPID   | SPEED_URL | Status |RPL| AML | Bus_Unit | Days ;
{==============================================================================================================================================================================================================================================================}
'0.001'    | '1%'      | '3W'    | '6PAD'    | 'CHIP'   | 'E74391-005'(!) = 'YES;YES;YES;UNK;ok;VLD' | 'E74391-005' | 'SMR2512D' | ''            | '0.001'  | '1%'   | '3W'    | 'DISCRETE' | 'RES_D,2512,1.00mOHM,1.00%,3W'               | '0.035 IN' | 'SMTOTHER'     | '2341' | 'http://speed.intel.com:8081/speed/module/pdm/item/pdm_item_detail_direct.asp?item_cde=E74391-005&item_rev=01&url_param=unused' | 'Design' | 'NO' | '2' | 'SMO_BOARDS' | '???' 
'0.001'    | '1%'      | '3W'    | '6PAD'    | 'EMPTY'  | 'E74391-005'(!) = 'YES;YES;YES;UNK;ok;VLD' | 'E74391-005' | 'SMR2512D' | ''            | 'NA'     | '1%'   | '3W'    | 'DISCRETE' | 'RES_D,2512,1.00mOHM,1.00%,3W'               | '0.035 IN' | 'SMTOTHER'     | '2341' | 'http://speed.intel.com:8081/speed/module/pdm/item/pdm_item_detail_direct.asp?item_cde=E74391-005&item_rev=01&url_param=unused' | 'Design' | 'NO' | '2' | 'SMO_BOARDS' | '???' 
END_PART
END.
